FILE_TYPE = CONNECTIVITY;
{Allegro Design Entry HDL 17.2-2016 S081 (4005846) 1/11/2022}
"PAGE_NUMBER" = 16;
0"NC";
1"M_G_CPU0_SA_DQ<31:0>";
2"M_G_CPU0_SB_DQ<31:0>";
3"M_G_CPU0_SA_CB<7:0>";
4"M_G_CPU0_SB_CB<7:0>";
5"M_G_CPU0_SA_DQS_DP<9:0>";
6"M_G_CPU0_SB_DQS_DP<9:0>";
7"M_G_CPU0_SA_CA<6:0>";
8"M_G_CPU0_SB_CA<6:0>";
9"M_G_CPU0_SA_DQS_DN<9:0>";
10"M_G_CPU0_SB_DQS_DN<9:0>";
11"M_G_CPU0_ALERT_N";
12"TP_M_G_CPU0_SA_TEST39G";
13"M_G_CPU0_ALERT_R_N";
14"M_G_CPU0_CLK_DN<0>";
15"M_G_CPU0_CLK_DP<0>";
16"M_G_CPU0_SA_CS_N<1>";
17"M_G_CPU0_SA_CS_N<0>";
18"M_G_CPU0_SA_PAR";
19"M_G_CPU0_SA_RSP<0>";
20"M_G_CPU0_SB_RSP<0>";
21"M_G_CPU0_SB_CS_N<0>";
22"M_G_CPU0_SB_CS_N<1>";
23"M_G_CPU0_SB_PAR";
24"M_G_CPU0_RESET_N";
25"M_G_CPU0_SB_CA<6>";
26"M_G_CPU0_SA_CA<6>";
27"M_G_CPU0_SB_CA<5>";
28"M_G_CPU0_SA_CA<5>";
29"M_G_CPU0_SB_CA<4>";
30"M_G_CPU0_SA_CA<4>";
31"M_G_CPU0_SB_CA<3>";
32"M_G_CPU0_SA_CA<3>";
33"M_G_CPU0_SB_CA<2>";
34"M_G_CPU0_SA_CA<2>";
35"M_G_CPU0_SB_CA<1>";
36"M_G_CPU0_SA_CA<1>";
37"M_G_CPU0_SB_CA<0>";
38"M_G_CPU0_SA_CA<0>";
39"M_G_CPU0_SB_DQS_DN<9>";
40"M_G_CPU0_SB_DQS_DP<9>";
41"M_G_CPU0_SB_DQS_DP<4>";
42"M_G_CPU0_SB_DQS_DN<8>";
43"M_G_CPU0_SB_DQS_DP<3>";
44"M_G_CPU0_SB_DQS_DN<7>";
45"M_G_CPU0_SB_DQS_DP<2>";
46"M_G_CPU0_SB_DQS_DN<6>";
47"M_G_CPU0_SB_DQS_DP<1>";
48"M_G_CPU0_SB_DQS_DN<5>";
49"M_G_CPU0_SB_DQS_DP<0>";
50"M_G_CPU0_SB_DQS_DN<4>";
51"M_G_CPU0_SA_DQS_DN<9>";
52"M_G_CPU0_SB_DQS_DN<3>";
53"M_G_CPU0_SB_DQS_DN<2>";
54"M_G_CPU0_SB_DQS_DN<1>";
55"M_G_CPU0_SB_DQS_DN<0>";
56"M_G_CPU0_SB_DQS_DP<8>";
57"M_G_CPU0_SB_DQS_DP<7>";
58"M_G_CPU0_SB_DQS_DP<6>";
59"M_G_CPU0_SB_DQS_DP<5>";
60"M_G_CPU0_SA_DQS_DP<9>";
61"M_G_CPU0_SA_DQS_DP<8>";
62"M_G_CPU0_SA_DQS_DP<7>";
63"M_G_CPU0_SA_DQS_DP<6>";
64"M_G_CPU0_SA_DQS_DP<5>";
65"M_G_CPU0_SA_DQS_DP<4>";
66"M_G_CPU0_SA_DQS_DN<8>";
67"M_G_CPU0_SA_DQS_DP<3>";
68"M_G_CPU0_SA_DQS_DN<7>";
69"M_G_CPU0_SA_DQS_DP<2>";
70"M_G_CPU0_SA_DQS_DN<6>";
71"M_G_CPU0_SA_DQS_DP<1>";
72"M_G_CPU0_SA_DQS_DN<5>";
73"M_G_CPU0_SA_DQS_DP<0>";
74"M_G_CPU0_SA_DQS_DN<4>";
75"M_G_CPU0_SA_DQS_DN<3>";
76"M_G_CPU0_SA_DQS_DN<2>";
77"M_G_CPU0_SA_DQS_DN<1>";
78"M_G_CPU0_SA_DQS_DN<0>";
79"M_G_CPU0_SB_CB<7>";
80"M_G_CPU0_SB_CB<6>";
81"M_G_CPU0_SB_CB<5>";
82"M_G_CPU0_SB_CB<4>";
83"M_G_CPU0_SB_CB<3>";
84"M_G_CPU0_SB_CB<2>";
85"M_G_CPU0_SB_CB<1>";
86"M_G_CPU0_SB_CB<0>";
87"M_G_CPU0_SA_CB<1>";
88"M_G_CPU0_SA_CB<0>";
89"M_G_CPU0_SB_DQ<29>";
90"M_G_CPU0_SB_DQ<28>";
91"M_G_CPU0_SB_DQ<27>";
92"M_G_CPU0_SB_DQ<26>";
93"M_G_CPU0_SB_DQ<25>";
94"M_G_CPU0_SB_DQ<24>";
95"M_G_CPU0_SB_DQ<23>";
96"M_G_CPU0_SB_DQ<22>";
97"M_G_CPU0_SA_CB<7>";
98"M_G_CPU0_SA_CB<6>";
99"M_G_CPU0_SB_DQ<31>";
100"M_G_CPU0_SA_CB<5>";
101"M_G_CPU0_SB_DQ<30>";
102"M_G_CPU0_SA_CB<4>";
103"M_G_CPU0_SA_CB<3>";
104"M_G_CPU0_SA_CB<2>";
105"M_G_CPU0_SB_DQ<19>";
106"M_G_CPU0_SB_DQ<18>";
107"M_G_CPU0_SB_DQ<17>";
108"M_G_CPU0_SB_DQ<16>";
109"M_G_CPU0_SB_DQ<15>";
110"M_G_CPU0_SB_DQ<14>";
111"M_G_CPU0_SB_DQ<9>";
112"M_G_CPU0_SB_DQ<13>";
113"M_G_CPU0_SB_DQ<8>";
114"M_G_CPU0_SB_DQ<12>";
115"M_G_CPU0_SB_DQ<7>";
116"M_G_CPU0_SB_DQ<11>";
117"M_G_CPU0_SB_DQ<6>";
118"M_G_CPU0_SB_DQ<10>";
119"M_G_CPU0_SB_DQ<21>";
120"M_G_CPU0_SB_DQ<5>";
121"M_G_CPU0_SB_DQ<20>";
122"M_G_CPU0_SB_DQ<4>";
123"M_G_CPU0_SA_DQ<21>";
124"M_G_CPU0_SB_DQ<0>";
125"M_G_CPU0_SA_DQ<20>";
126"M_G_CPU0_SA_DQ<31>";
127"M_G_CPU0_SA_DQ<30>";
128"M_G_CPU0_SA_DQ<19>";
129"M_G_CPU0_SA_DQ<18>";
130"M_G_CPU0_SA_DQ<29>";
131"M_G_CPU0_SA_DQ<17>";
132"M_G_CPU0_SA_DQ<28>";
133"M_G_CPU0_SA_DQ<27>";
134"M_G_CPU0_SA_DQ<26>";
135"M_G_CPU0_SA_DQ<25>";
136"M_G_CPU0_SA_DQ<24>";
137"M_G_CPU0_SB_DQ<3>";
138"M_G_CPU0_SA_DQ<23>";
139"M_G_CPU0_SB_DQ<2>";
140"M_G_CPU0_SA_DQ<22>";
141"M_G_CPU0_SB_DQ<1>";
142"M_G_CPU0_SA_DQ<0>";
143"M_G_CPU0_SA_DQ<10>";
144"M_G_CPU0_SA_DQ<9>";
145"M_G_CPU0_SA_DQ<8>";
146"M_G_CPU0_SA_DQ<7>";
147"M_G_CPU0_SA_DQ<6>";
148"M_G_CPU0_SA_DQ<16>";
149"M_G_CPU0_SA_DQ<5>";
150"M_G_CPU0_SA_DQ<15>";
151"M_G_CPU0_SA_DQ<4>";
152"M_G_CPU0_SA_DQ<14>";
153"M_G_CPU0_SA_DQ<3>";
154"M_G_CPU0_SA_DQ<13>";
155"M_G_CPU0_SA_DQ<2>";
156"M_G_CPU0_SA_DQ<12>";
157"M_G_CPU0_SA_DQ<1>";
158"M_G_CPU0_SA_DQ<11>";
%"GENOA_SP5"
"7","(-4700,3675)","0","pure_quanta","I167";
;
LOCATION"U25"
$SEC"7"
CDS_SEC"7"
PART_TYPE"SMLF"
MATERIAL"IO"
VALUE"SOCKET6096_13568-001"
PART_NUMBER"DGA^6000030"
CDS_LIB"pure_quanta"
CDS_LMAN_SYM_OUTLINE"-650,2525,650,-2525"
NEEDS_NO_SIZE"TRUE";
"TEST39G"
$PN"BF4"12;
"MG1_CLK_L"
$PN"BG2"0;
"MG1_CLK_H"
$PN"BF2"0;
"MG0_CLK_L"
$PN"BD2"14;
"MG0_CLK_H"
$PN"BC2"15;
"MGA_PAR"
$PN"BC3"18;
"MGB_DQS_H9"
$PN"BV2"40;
"MGB_PAR"
$PN"BL3"23;
"MGA_CHECK1"
$PN"AK4"87;
"MGA_DATA0"
$PN"E2"142;
"MGA_DATA10"
$PN"M2"143;
"MGA_DATA21"
$PN"AB4"123;
"MGB_DATA0"
$PN"CB2"124;
"MGB_DQS_H4"
$PN"BY4"41;
"MGB_DQS_L8"
$PN"DC3"42;
"MGA_CHECK0"
$PN"AJ2"88;
"MGA_DATA20"
$PN"AA2"125;
"MGA_DATA31"
$PN"AJ3"126;
"MGA_DQS_H9"
$PN"AN3"60;
"MGB_DQS_H3"
$PN"DB2"43;
"MGB_DQS_L7"
$PN"CU3"44;
"MGA0_CS_L1"
$PN"AV4"16;
"MGA1_CS_L1"
$PN"AW3"0;
"MGA_DATA30"
$PN"AH2"127;
"MGA_DQS_H8"
$PN"AG3"61;
"MGB_DATA19"
$PN"CT4"105;
"MGB_DQS_H2"
$PN"CT2"45;
"MGB_DQS_L6"
$PN"CL3"46;
"MGA0_CS_L0"
$PN"AU2"17;
"MGA1_CS_L0"
$PN"AV2"0;
"MGA_DQS_H7"
$PN"AA3"62;
"MGB_DATA18"
$PN"CR2"106;
"MGB_DATA29"
$PN"DE3"89;
"MGB_DQS_H1"
$PN"CK2"47;
"MGB_DQS_L5"
$PN"CE3"48;
"MGA_DQS_H6"
$PN"R3"63;
"MGB_DATA17"
$PN"CR3"107;
"MGB_DATA28"
$PN"DD2"90;
"MGB_DQS_H0"
$PN"CD2"49;
"MGB_DQS_L4"
$PN"BW3"50;
"MGA_DQS_H5"
$PN"J3"64;
"MGA_DQS_L9"
$PN"AM4"51;
"MGB0_RSP_L"
$PN"BP2"20;
"MGB1_RSP_L"
$PN"BR2"0;
"MGB_CHECK7"
$PN"BV4"79;
"MGB_DATA16"
$PN"CP2"108;
"MGB_DATA27"
$PN"DB4"91;
"MGB_DQS_L3"
$PN"DC2"52;
"MGA_DQS_H4"
$PN"AL2"65;
"MGA_DQS_L8"
$PN"AF4"66;
"MGB_CA6"
$PN"BK2"25;
"MGB_CHECK6"
$PN"BU2"80;
"MGB_DATA15"
$PN"CP4"109;
"MGB_DATA26"
$PN"DA2"92;
"MGB_DQS_L2"
$PN"CU2"53;
"MGA_CA6"
$PN"BB4"26;
"MGA_DQS_H3"
$PN"AE2"67;
"MGA_DQS_L7"
$PN"Y4"68;
"MGB_CA5"
$PN"BK4"27;
"MGB_CHECK5"
$PN"BU3"81;
"MGB_DATA14"
$PN"CN2"110;
"MGB_DATA25"
$PN"DA3"93;
"MGB_DQS_L1"
$PN"CL2"54;
"MGA_CA5"
$PN"BB2"28;
"MGA_DATA9"
$PN"M4"144;
"MGA_DATA19"
$PN"W3"128;
"MGA_DQS_H2"
$PN"W2"69;
"MGA_DQS_L6"
$PN"P4"70;
"MGB_CA4"
$PN"BJ3"29;
"MGB_CHECK4"
$PN"BT2"82;
"MGB_DATA9"
$PN"CJ3"111;
"MGB_DATA13"
$PN"CN3"112;
"MGB_DATA24"
$PN"CY2"94;
"MGB_DQS_L0"
$PN"CE2"55;
"MGA_CA4"
$PN"BA2"30;
"MGA_DATA8"
$PN"L2"145;
"MGA_DATA18"
$PN"V2"129;
"MGA_DATA29"
$PN"AH4"130;
"MGA_DQS_H1"
$PN"N2"71;
"MGA_DQS_L5"
$PN"H4"72;
"MGB_CA3"
$PN"BJ2"31;
"MGB_CHECK3"
$PN"CB4"83;
"MGB_DATA8"
$PN"CH2"113;
"MGB_DATA12"
$PN"CM2"114;
"MGB_DATA23"
$PN"CY4"95;
"MGA_CA3"
$PN"BA3"32;
"MGA_DATA7"
$PN"L3"146;
"MGA_DATA17"
$PN"V4"131;
"MGA_DATA28"
$PN"AG2"132;
"MGA_DQS_H0"
$PN"G2"73;
"MGA_DQS_L4"
$PN"AM2"74;
"MGB_CA2"
$PN"BH2"33;
"MGB_CHECK2"
$PN"CA2"84;
"MGB_DATA7"
$PN"CH4"115;
"MGB_DATA11"
$PN"CK4"116;
"MGB_DATA22"
$PN"CW2"96;
"MGA0_RSP_L"
$PN"BN3"19;
"MGA1_RSP_L"
$PN"BP4"0;
"MGA_CA2"
$PN"AY4"34;
"MGA_CHECK7"
$PN"AR3"97;
"MGA_DATA6"
$PN"K2"147;
"MGA_DATA16"
$PN"U2"148;
"MGA_DATA27"
$PN"AE3"133;
"MGA_DQS_L3"
$PN"AF2"75;
"MGB_CA1"
$PN"BH4"35;
"MGB_CHECK1"
$PN"CA3"85;
"MGB_DATA6"
$PN"CG2"117;
"MGB_DATA10"
$PN"CJ2"118;
"MGB_DATA21"
$PN"CW3"119;
"MGA_CA1"
$PN"AY2"36;
"MGA_CHECK6"
$PN"AP2"98;
"MGA_DATA5"
$PN"K4"149;
"MGA_DATA15"
$PN"U3"150;
"MGA_DATA26"
$PN"AD2"134;
"MGA_DQS_L2"
$PN"Y2"76;
"MGB_CA0"
$PN"BG3"37;
"MGB_CHECK0"
$PN"BY2"86;
"MGB_DATA5"
$PN"CG3"120;
"MGB_DATA20"
$PN"CV2"121;
"MGB_DATA31"
$PN"DF2"99;
"MGA_CA0"
$PN"AW2"38;
"MGA_CHECK5"
$PN"AP4"100;
"MGA_DATA4"
$PN"J2"151;
"MGA_DATA14"
$PN"T2"152;
"MGA_DATA25"
$PN"AD4"135;
"MGA_DQS_L1"
$PN"P2"77;
"MGB0_CS_L1"
$PN"BN2"22;
"MGB1_CS_L1"
$PN"BM2"0;
"MGB_DATA4"
$PN"CF2"122;
"MGB_DATA30"
$PN"DE2"101;
"MGB_DQS_H8"
$PN"DD4"56;
"MGA_CHECK4"
$PN"AN2"102;
"MGA_DATA3"
$PN"G3"153;
"MGA_DATA13"
$PN"T4"154;
"MGA_DATA24"
$PN"AC2"136;
"MGA_DQS_L0"
$PN"H2"78;
"MGB0_CS_L0"
$PN"BM4"21;
"MGB1_CS_L0"
$PN"BL2"0;
"MGB_DATA3"
$PN"CD4"137;
"MGB_DQS_H7"
$PN"CV4"57;
"MGA_CHECK3"
$PN"AL3"103;
"MGA_DATA2"
$PN"F2"155;
"MGA_DATA12"
$PN"R2"156;
"MGA_DATA23"
$PN"AC3"138;
"MGB_DATA2"
$PN"CC2"139;
"MGB_DQS_H6"
$PN"CM4"58;
"MGA_CHECK2"
$PN"AK2"104;
"MGA_DATA1"
$PN"F4"157;
"MGA_DATA11"
$PN"N3"158;
"MGA_DATA22"
$PN"AB2"140;
"MGB_DATA1"
$PN"CC3"141;
"MGB_DQS_H5"
$PN"CF4"59;
"MGB_DQS_L9"
$PN"BW2"39;
"MG_RESET_L"
$PN"AT2"24;
"MG_ALERT_L"
$PN"AR2"13;
%"TAP"
"1","(-3425,6050)","0","mstr_standard","I170";
;
CDS_LIB"mstr_standard"
BODY_TYPE"PLUMBING"
HDL_TAP"TRUE";
"B \NAC \NWC"1;
"S \NAC"
BN"0"142;
%"TAP"
"1","(-3425,6000)","0","mstr_standard","I171";
;
CDS_LIB"mstr_standard"
BODY_TYPE"PLUMBING"
HDL_TAP"TRUE";
"B \NAC \NWC"1;
"S \NAC"
BN"1"157;
%"TAP"
"1","(-3425,5950)","0","mstr_standard","I172";
;
CDS_LIB"mstr_standard"
BODY_TYPE"PLUMBING"
HDL_TAP"TRUE";
"B \NAC \NWC"1;
"S \NAC"
BN"2"155;
%"TAP"
"1","(-3425,5900)","0","mstr_standard","I173";
;
CDS_LIB"mstr_standard"
BODY_TYPE"PLUMBING"
HDL_TAP"TRUE";
"B \NAC \NWC"1;
"S \NAC"
BN"3"153;
%"TAP"
"1","(-3425,5850)","0","mstr_standard","I174";
;
CDS_LIB"mstr_standard"
BODY_TYPE"PLUMBING"
HDL_TAP"TRUE";
"B \NAC \NWC"1;
"S \NAC"
BN"4"151;
%"TAP"
"1","(-3425,5800)","0","mstr_standard","I175";
;
CDS_LIB"mstr_standard"
BODY_TYPE"PLUMBING"
HDL_TAP"TRUE";
"B \NAC \NWC"1;
"S \NAC"
BN"5"149;
%"TAP"
"1","(-3425,5700)","0","mstr_standard","I176";
;
CDS_LIB"mstr_standard"
BODY_TYPE"PLUMBING"
HDL_TAP"TRUE";
"B \NAC \NWC"1;
"S \NAC"
BN"7"146;
%"TAP"
"1","(-3425,5750)","0","mstr_standard","I177";
;
CDS_LIB"mstr_standard"
BODY_TYPE"PLUMBING"
HDL_TAP"TRUE";
"B \NAC \NWC"1;
"S \NAC"
BN"6"147;
%"TAP"
"1","(-3425,5600)","0","mstr_standard","I178";
;
CDS_LIB"mstr_standard"
BODY_TYPE"PLUMBING"
HDL_TAP"TRUE";
"B \NAC \NWC"1;
"S \NAC"
BN"8"145;
%"TAP"
"1","(-3425,5550)","0","mstr_standard","I179";
;
CDS_LIB"mstr_standard"
BODY_TYPE"PLUMBING"
HDL_TAP"TRUE";
"B \NAC \NWC"1;
"S \NAC"
BN"9"144;
%"TAP"
"1","(-3425,5450)","0","mstr_standard","I180";
;
CDS_LIB"mstr_standard"
BODY_TYPE"PLUMBING"
HDL_TAP"TRUE";
"B \NAC \NWC"1;
"S \NAC"
BN"11"158;
%"TAP"
"1","(-3425,5500)","0","mstr_standard","I181";
;
CDS_LIB"mstr_standard"
BODY_TYPE"PLUMBING"
HDL_TAP"TRUE";
"B \NAC \NWC"1;
"S \NAC"
BN"10"143;
%"TAP"
"1","(-3425,5400)","0","mstr_standard","I182";
;
CDS_LIB"mstr_standard"
BODY_TYPE"PLUMBING"
HDL_TAP"TRUE";
"B \NAC \NWC"1;
"S \NAC"
BN"12"156;
%"TAP"
"1","(-3425,5350)","0","mstr_standard","I183";
;
CDS_LIB"mstr_standard"
BODY_TYPE"PLUMBING"
HDL_TAP"TRUE";
"B \NAC \NWC"1;
"S \NAC"
BN"13"154;
%"TAP"
"1","(-3425,5250)","0","mstr_standard","I184";
;
CDS_LIB"mstr_standard"
BODY_TYPE"PLUMBING"
HDL_TAP"TRUE";
"B \NAC \NWC"1;
"S \NAC"
BN"15"150;
%"TAP"
"1","(-3425,5300)","0","mstr_standard","I185";
;
CDS_LIB"mstr_standard"
BODY_TYPE"PLUMBING"
HDL_TAP"TRUE";
"B \NAC \NWC"1;
"S \NAC"
BN"14"152;
%"TAP"
"1","(-3425,5150)","0","mstr_standard","I186";
;
CDS_LIB"mstr_standard"
BODY_TYPE"PLUMBING"
HDL_TAP"TRUE";
"B \NAC \NWC"1;
"S \NAC"
BN"16"148;
%"TAP"
"1","(-3425,5100)","0","mstr_standard","I187";
;
CDS_LIB"mstr_standard"
BODY_TYPE"PLUMBING"
HDL_TAP"TRUE";
"B \NAC \NWC"1;
"S \NAC"
BN"17"131;
%"TAP"
"1","(-3425,5050)","0","mstr_standard","I188";
;
CDS_LIB"mstr_standard"
BODY_TYPE"PLUMBING"
HDL_TAP"TRUE";
"B \NAC \NWC"1;
"S \NAC"
BN"18"129;
%"TAP"
"1","(-3425,5000)","0","mstr_standard","I189";
;
CDS_LIB"mstr_standard"
BODY_TYPE"PLUMBING"
HDL_TAP"TRUE";
"B \NAC \NWC"1;
"S \NAC"
BN"19"128;
%"TAP"
"1","(-3425,4950)","0","mstr_standard","I190";
;
CDS_LIB"mstr_standard"
BODY_TYPE"PLUMBING"
HDL_TAP"TRUE";
"B \NAC \NWC"1;
"S \NAC"
BN"20"125;
%"TAP"
"1","(-3425,4900)","0","mstr_standard","I191";
;
CDS_LIB"mstr_standard"
BODY_TYPE"PLUMBING"
HDL_TAP"TRUE";
"B \NAC \NWC"1;
"S \NAC"
BN"21"123;
%"TAP"
"1","(-3425,4800)","0","mstr_standard","I192";
;
CDS_LIB"mstr_standard"
BODY_TYPE"PLUMBING"
HDL_TAP"TRUE";
"B \NAC \NWC"1;
"S \NAC"
BN"23"138;
%"TAP"
"1","(-3425,4850)","0","mstr_standard","I193";
;
CDS_LIB"mstr_standard"
BODY_TYPE"PLUMBING"
HDL_TAP"TRUE";
"B \NAC \NWC"1;
"S \NAC"
BN"22"140;
%"TAP"
"1","(-3425,4700)","0","mstr_standard","I194";
;
CDS_LIB"mstr_standard"
BODY_TYPE"PLUMBING"
HDL_TAP"TRUE";
"B \NAC \NWC"1;
"S \NAC"
BN"24"136;
%"TAP"
"1","(-3425,4650)","0","mstr_standard","I195";
;
CDS_LIB"mstr_standard"
BODY_TYPE"PLUMBING"
HDL_TAP"TRUE";
"B \NAC \NWC"1;
"S \NAC"
BN"25"135;
%"TAP"
"1","(-3425,4550)","0","mstr_standard","I196";
;
CDS_LIB"mstr_standard"
BODY_TYPE"PLUMBING"
HDL_TAP"TRUE";
"B \NAC \NWC"1;
"S \NAC"
BN"27"133;
%"TAP"
"1","(-3425,4600)","0","mstr_standard","I197";
;
CDS_LIB"mstr_standard"
BODY_TYPE"PLUMBING"
HDL_TAP"TRUE";
"B \NAC \NWC"1;
"S \NAC"
BN"26"134;
%"TAP"
"1","(-3425,4500)","0","mstr_standard","I198";
;
CDS_LIB"mstr_standard"
BODY_TYPE"PLUMBING"
HDL_TAP"TRUE";
"B \NAC \NWC"1;
"S \NAC"
BN"28"132;
%"TAP"
"1","(-3425,4450)","0","mstr_standard","I199";
;
CDS_LIB"mstr_standard"
BODY_TYPE"PLUMBING"
HDL_TAP"TRUE";
"B \NAC \NWC"1;
"S \NAC"
BN"29"130;
%"TAP"
"1","(-3425,4400)","0","mstr_standard","I200";
;
CDS_LIB"mstr_standard"
BODY_TYPE"PLUMBING"
HDL_TAP"TRUE";
"B \NAC \NWC"1;
"S \NAC"
BN"30"127;
%"TAP"
"1","(-3425,4250)","0","mstr_standard","I201";
;
CDS_LIB"mstr_standard"
BODY_TYPE"PLUMBING"
HDL_TAP"TRUE";
"B \NAC \NWC"2;
"S \NAC"
BN"0"124;
%"TAP"
"1","(-3425,4350)","0","mstr_standard","I202";
;
CDS_LIB"mstr_standard"
BODY_TYPE"PLUMBING"
HDL_TAP"TRUE";
"B \NAC \NWC"1;
"S \NAC"
BN"31"126;
%"TAP"
"1","(-3425,4200)","0","mstr_standard","I203";
;
CDS_LIB"mstr_standard"
BODY_TYPE"PLUMBING"
HDL_TAP"TRUE";
"B \NAC \NWC"2;
"S \NAC"
BN"1"141;
%"TAP"
"1","(-3425,4150)","0","mstr_standard","I204";
;
CDS_LIB"mstr_standard"
BODY_TYPE"PLUMBING"
HDL_TAP"TRUE";
"B \NAC \NWC"2;
"S \NAC"
BN"2"139;
%"TAP"
"1","(-3425,4100)","0","mstr_standard","I205";
;
CDS_LIB"mstr_standard"
BODY_TYPE"PLUMBING"
HDL_TAP"TRUE";
"B \NAC \NWC"2;
"S \NAC"
BN"3"137;
%"TAP"
"1","(-3425,4050)","0","mstr_standard","I207";
;
CDS_LIB"mstr_standard"
BODY_TYPE"PLUMBING"
HDL_TAP"TRUE";
"B \NAC \NWC"2;
"S \NAC"
BN"4"122;
%"TAP"
"1","(-3425,4000)","0","mstr_standard","I208";
;
CDS_LIB"mstr_standard"
BODY_TYPE"PLUMBING"
HDL_TAP"TRUE";
"B \NAC \NWC"2;
"S \NAC"
BN"5"120;
%"TAP"
"1","(-3425,3900)","0","mstr_standard","I209";
;
CDS_LIB"mstr_standard"
BODY_TYPE"PLUMBING"
HDL_TAP"TRUE";
"B \NAC \NWC"2;
"S \NAC"
BN"7"115;
%"TAP"
"1","(-3425,3950)","0","mstr_standard","I210";
;
CDS_LIB"mstr_standard"
BODY_TYPE"PLUMBING"
HDL_TAP"TRUE";
"B \NAC \NWC"2;
"S \NAC"
BN"6"117;
%"TAP"
"1","(-3425,3800)","0","mstr_standard","I211";
;
CDS_LIB"mstr_standard"
BODY_TYPE"PLUMBING"
HDL_TAP"TRUE";
"B \NAC \NWC"2;
"S \NAC"
BN"8"113;
%"TAP"
"1","(-3425,3750)","0","mstr_standard","I212";
;
CDS_LIB"mstr_standard"
BODY_TYPE"PLUMBING"
HDL_TAP"TRUE";
"B \NAC \NWC"2;
"S \NAC"
BN"9"111;
%"TAP"
"1","(-3425,3650)","0","mstr_standard","I213";
;
CDS_LIB"mstr_standard"
BODY_TYPE"PLUMBING"
HDL_TAP"TRUE";
"B \NAC \NWC"2;
"S \NAC"
BN"11"116;
%"TAP"
"1","(-3425,3700)","0","mstr_standard","I214";
;
CDS_LIB"mstr_standard"
BODY_TYPE"PLUMBING"
HDL_TAP"TRUE";
"B \NAC \NWC"2;
"S \NAC"
BN"10"118;
%"TAP"
"1","(-3425,3600)","0","mstr_standard","I215";
;
CDS_LIB"mstr_standard"
BODY_TYPE"PLUMBING"
HDL_TAP"TRUE";
"B \NAC \NWC"2;
"S \NAC"
BN"12"114;
%"TAP"
"1","(-3425,3550)","0","mstr_standard","I216";
;
CDS_LIB"mstr_standard"
BODY_TYPE"PLUMBING"
HDL_TAP"TRUE";
"B \NAC \NWC"2;
"S \NAC"
BN"13"112;
%"TAP"
"1","(-3425,3500)","0","mstr_standard","I217";
;
CDS_LIB"mstr_standard"
BODY_TYPE"PLUMBING"
HDL_TAP"TRUE";
"B \NAC \NWC"2;
"S \NAC"
BN"14"110;
%"TAP"
"1","(-3425,3350)","0","mstr_standard","I218";
;
CDS_LIB"mstr_standard"
BODY_TYPE"PLUMBING"
HDL_TAP"TRUE";
"B \NAC \NWC"2;
"S \NAC"
BN"16"108;
%"TAP"
"1","(-3425,3450)","0","mstr_standard","I219";
;
CDS_LIB"mstr_standard"
BODY_TYPE"PLUMBING"
HDL_TAP"TRUE";
"B \NAC \NWC"2;
"S \NAC"
BN"15"109;
%"TAP"
"1","(-3425,3300)","0","mstr_standard","I220";
;
CDS_LIB"mstr_standard"
BODY_TYPE"PLUMBING"
HDL_TAP"TRUE";
"B \NAC \NWC"2;
"S \NAC"
BN"17"107;
%"TAP"
"1","(-3425,3250)","0","mstr_standard","I221";
;
CDS_LIB"mstr_standard"
BODY_TYPE"PLUMBING"
HDL_TAP"TRUE";
"B \NAC \NWC"2;
"S \NAC"
BN"18"106;
%"TAP"
"1","(-3425,3200)","0","mstr_standard","I222";
;
CDS_LIB"mstr_standard"
BODY_TYPE"PLUMBING"
HDL_TAP"TRUE";
"B \NAC \NWC"2;
"S \NAC"
BN"19"105;
%"TAP"
"1","(-3425,3150)","0","mstr_standard","I223";
;
CDS_LIB"mstr_standard"
BODY_TYPE"PLUMBING"
HDL_TAP"TRUE";
"B \NAC \NWC"2;
"S \NAC"
BN"20"121;
%"TAP"
"1","(-3425,3100)","0","mstr_standard","I224";
;
CDS_LIB"mstr_standard"
BODY_TYPE"PLUMBING"
HDL_TAP"TRUE";
"B \NAC \NWC"2;
"S \NAC"
BN"21"119;
%"TAP"
"1","(-3425,3050)","0","mstr_standard","I225";
;
CDS_LIB"mstr_standard"
BODY_TYPE"PLUMBING"
HDL_TAP"TRUE";
"B \NAC \NWC"2;
"S \NAC"
BN"22"96;
%"TAP"
"1","(-3425,3000)","0","mstr_standard","I226";
;
CDS_LIB"mstr_standard"
BODY_TYPE"PLUMBING"
HDL_TAP"TRUE";
"B \NAC \NWC"2;
"S \NAC"
BN"23"95;
%"TAP"
"1","(-3425,2900)","0","mstr_standard","I227";
;
CDS_LIB"mstr_standard"
BODY_TYPE"PLUMBING"
HDL_TAP"TRUE";
"B \NAC \NWC"2;
"S \NAC"
BN"24"94;
%"TAP"
"1","(-3425,2850)","0","mstr_standard","I228";
;
CDS_LIB"mstr_standard"
BODY_TYPE"PLUMBING"
HDL_TAP"TRUE";
"B \NAC \NWC"2;
"S \NAC"
BN"25"93;
%"TAP"
"1","(-3425,2800)","0","mstr_standard","I229";
;
CDS_LIB"mstr_standard"
BODY_TYPE"PLUMBING"
HDL_TAP"TRUE";
"B \NAC \NWC"2;
"S \NAC"
BN"26"92;
%"TAP"
"1","(-3425,2750)","0","mstr_standard","I230";
;
CDS_LIB"mstr_standard"
BODY_TYPE"PLUMBING"
HDL_TAP"TRUE";
"B \NAC \NWC"2;
"S \NAC"
BN"27"91;
%"TAP"
"1","(-3425,2700)","0","mstr_standard","I231";
;
CDS_LIB"mstr_standard"
BODY_TYPE"PLUMBING"
HDL_TAP"TRUE";
"B \NAC \NWC"2;
"S \NAC"
BN"28"90;
%"TAP"
"1","(-3425,2650)","0","mstr_standard","I232";
;
CDS_LIB"mstr_standard"
BODY_TYPE"PLUMBING"
HDL_TAP"TRUE";
"B \NAC \NWC"2;
"S \NAC"
BN"29"89;
%"TAP"
"1","(-3425,2600)","0","mstr_standard","I233";
;
CDS_LIB"mstr_standard"
BODY_TYPE"PLUMBING"
HDL_TAP"TRUE";
"B \NAC \NWC"2;
"S \NAC"
BN"30"101;
%"TAP"
"1","(-3425,2450)","0","mstr_standard","I234";
;
CDS_LIB"mstr_standard"
BODY_TYPE"PLUMBING"
HDL_TAP"TRUE";
"B \NAC \NWC"3;
"S \NAC"
BN"0"88;
%"TAP"
"1","(-3425,2550)","0","mstr_standard","I235";
;
CDS_LIB"mstr_standard"
BODY_TYPE"PLUMBING"
HDL_TAP"TRUE";
"B \NAC \NWC"2;
"S \NAC"
BN"31"99;
%"TAP"
"1","(-3425,2400)","0","mstr_standard","I236";
;
CDS_LIB"mstr_standard"
BODY_TYPE"PLUMBING"
HDL_TAP"TRUE";
"B \NAC \NWC"3;
"S \NAC"
BN"1"87;
%"TAP"
"1","(-3425,2350)","0","mstr_standard","I237";
;
CDS_LIB"mstr_standard"
BODY_TYPE"PLUMBING"
HDL_TAP"TRUE";
"B \NAC \NWC"3;
"S \NAC"
BN"2"104;
%"TAP"
"1","(-3425,2250)","0","mstr_standard","I238";
;
CDS_LIB"mstr_standard"
BODY_TYPE"PLUMBING"
HDL_TAP"TRUE";
"B \NAC \NWC"3;
"S \NAC"
BN"4"102;
%"TAP"
"1","(-3425,2300)","0","mstr_standard","I239";
;
CDS_LIB"mstr_standard"
BODY_TYPE"PLUMBING"
HDL_TAP"TRUE";
"B \NAC \NWC"3;
"S \NAC"
BN"3"103;
%"TAP"
"1","(-3425,2200)","0","mstr_standard","I240";
;
CDS_LIB"mstr_standard"
BODY_TYPE"PLUMBING"
HDL_TAP"TRUE";
"B \NAC \NWC"3;
"S \NAC"
BN"5"100;
%"TAP"
"1","(-3425,2100)","0","mstr_standard","I241";
;
CDS_LIB"mstr_standard"
BODY_TYPE"PLUMBING"
HDL_TAP"TRUE";
"B \NAC \NWC"3;
"S \NAC"
BN"7"97;
%"TAP"
"1","(-3425,2150)","0","mstr_standard","I242";
;
CDS_LIB"mstr_standard"
BODY_TYPE"PLUMBING"
HDL_TAP"TRUE";
"B \NAC \NWC"3;
"S \NAC"
BN"6"98;
%"TAP"
"1","(-3425,2000)","0","mstr_standard","I244";
;
CDS_LIB"mstr_standard"
BODY_TYPE"PLUMBING"
HDL_TAP"TRUE";
"B \NAC \NWC"4;
"S \NAC"
BN"0"86;
%"TAP"
"1","(-3425,1950)","0","mstr_standard","I245";
;
CDS_LIB"mstr_standard"
BODY_TYPE"PLUMBING"
HDL_TAP"TRUE";
"B \NAC \NWC"4;
"S \NAC"
BN"1"85;
%"TAP"
"1","(-3425,1900)","0","mstr_standard","I246";
;
CDS_LIB"mstr_standard"
BODY_TYPE"PLUMBING"
HDL_TAP"TRUE";
"B \NAC \NWC"4;
"S \NAC"
BN"2"84;
%"TAP"
"1","(-3425,1850)","0","mstr_standard","I247";
;
CDS_LIB"mstr_standard"
BODY_TYPE"PLUMBING"
HDL_TAP"TRUE";
"B \NAC \NWC"4;
"S \NAC"
BN"3"83;
%"TAP"
"1","(-3425,1800)","0","mstr_standard","I248";
;
CDS_LIB"mstr_standard"
BODY_TYPE"PLUMBING"
HDL_TAP"TRUE";
"B \NAC \NWC"4;
"S \NAC"
BN"4"82;
%"TAP"
"1","(-3425,1750)","0","mstr_standard","I249";
;
CDS_LIB"mstr_standard"
BODY_TYPE"PLUMBING"
HDL_TAP"TRUE";
"B \NAC \NWC"4;
"S \NAC"
BN"5"81;
%"TAP"
"1","(-3425,1700)","0","mstr_standard","I250";
;
CDS_LIB"mstr_standard"
BODY_TYPE"PLUMBING"
HDL_TAP"TRUE";
"B \NAC \NWC"4;
"S \NAC"
BN"6"80;
%"TAP"
"1","(-3425,1650)","0","mstr_standard","I251";
;
CDS_LIB"mstr_standard"
BODY_TYPE"PLUMBING"
HDL_TAP"TRUE";
"B \NAC \NWC"4;
"S \NAC"
BN"7"79;
%"TAP"
"1","(-5850,6050)","2","mstr_standard","I252";
;
CDS_LIB"mstr_standard"
BODY_TYPE"PLUMBING"
HDL_TAP"TRUE";
"B \NAC \NWC"5;
"S \NAC"
BN"0"73;
%"TAP"
"1","(-5850,5950)","2","mstr_standard","I253";
;
CDS_LIB"mstr_standard"
BODY_TYPE"PLUMBING"
HDL_TAP"TRUE";
"B \NAC \NWC"5;
"S \NAC"
BN"1"71;
%"TAP"
"1","(-5850,5850)","2","mstr_standard","I254";
;
CDS_LIB"mstr_standard"
BODY_TYPE"PLUMBING"
HDL_TAP"TRUE";
"B \NAC \NWC"5;
"S \NAC"
BN"2"69;
%"TAP"
"1","(-5850,5750)","2","mstr_standard","I255";
;
CDS_LIB"mstr_standard"
BODY_TYPE"PLUMBING"
HDL_TAP"TRUE";
"B \NAC \NWC"5;
"S \NAC"
BN"3"67;
%"TAP"
"1","(-5850,5650)","2","mstr_standard","I256";
;
CDS_LIB"mstr_standard"
BODY_TYPE"PLUMBING"
HDL_TAP"TRUE";
"B \NAC \NWC"5;
"S \NAC"
BN"4"65;
%"TAP"
"1","(-6050,6000)","2","mstr_standard","I257";
;
CDS_LIB"mstr_standard"
BODY_TYPE"PLUMBING"
HDL_TAP"TRUE";
"B \NAC \NWC"9;
"S \NAC"
BN"0"78;
%"TAP"
"1","(-6050,5900)","2","mstr_standard","I258";
;
CDS_LIB"mstr_standard"
BODY_TYPE"PLUMBING"
HDL_TAP"TRUE";
"B \NAC \NWC"9;
"S \NAC"
BN"1"77;
%"TAP"
"1","(-6050,5800)","2","mstr_standard","I259";
;
CDS_LIB"mstr_standard"
BODY_TYPE"PLUMBING"
HDL_TAP"TRUE";
"B \NAC \NWC"9;
"S \NAC"
BN"2"76;
%"TAP"
"1","(-6050,5700)","2","mstr_standard","I260";
;
CDS_LIB"mstr_standard"
BODY_TYPE"PLUMBING"
HDL_TAP"TRUE";
"B \NAC \NWC"9;
"S \NAC"
BN"3"75;
%"TAP"
"1","(-5850,5450)","2","mstr_standard","I261";
;
CDS_LIB"mstr_standard"
BODY_TYPE"PLUMBING"
HDL_TAP"TRUE";
"B \NAC \NWC"5;
"S \NAC"
BN"6"63;
%"TAP"
"1","(-5850,5550)","2","mstr_standard","I262";
;
CDS_LIB"mstr_standard"
BODY_TYPE"PLUMBING"
HDL_TAP"TRUE";
"B \NAC \NWC"5;
"S \NAC"
BN"5"64;
%"TAP"
"1","(-5850,5350)","2","mstr_standard","I263";
;
CDS_LIB"mstr_standard"
BODY_TYPE"PLUMBING"
HDL_TAP"TRUE";
"B \NAC \NWC"5;
"S \NAC"
BN"7"62;
%"TAP"
"1","(-5850,5250)","2","mstr_standard","I264";
;
CDS_LIB"mstr_standard"
BODY_TYPE"PLUMBING"
HDL_TAP"TRUE";
"B \NAC \NWC"5;
"S \NAC"
BN"8"61;
%"TAP"
"1","(-5850,5150)","2","mstr_standard","I265";
;
CDS_LIB"mstr_standard"
BODY_TYPE"PLUMBING"
HDL_TAP"TRUE";
"B \NAC \NWC"5;
"S \NAC"
BN"9"60;
%"TAP"
"1","(-6050,5600)","2","mstr_standard","I266";
;
CDS_LIB"mstr_standard"
BODY_TYPE"PLUMBING"
HDL_TAP"TRUE";
"B \NAC \NWC"9;
"S \NAC"
BN"4"74;
%"TAP"
"1","(-6050,5500)","2","mstr_standard","I267";
;
CDS_LIB"mstr_standard"
BODY_TYPE"PLUMBING"
HDL_TAP"TRUE";
"B \NAC \NWC"9;
"S \NAC"
BN"5"72;
%"TAP"
"1","(-6050,5400)","2","mstr_standard","I268";
;
CDS_LIB"mstr_standard"
BODY_TYPE"PLUMBING"
HDL_TAP"TRUE";
"B \NAC \NWC"9;
"S \NAC"
BN"6"70;
%"TAP"
"1","(-6050,5300)","2","mstr_standard","I269";
;
CDS_LIB"mstr_standard"
BODY_TYPE"PLUMBING"
HDL_TAP"TRUE";
"B \NAC \NWC"9;
"S \NAC"
BN"7"68;
%"TAP"
"1","(-6050,5200)","2","mstr_standard","I270";
;
CDS_LIB"mstr_standard"
BODY_TYPE"PLUMBING"
HDL_TAP"TRUE";
"B \NAC \NWC"9;
"S \NAC"
BN"8"66;
%"TAP"
"1","(-5850,5000)","2","mstr_standard","I271";
;
CDS_LIB"mstr_standard"
BODY_TYPE"PLUMBING"
HDL_TAP"TRUE";
"B \NAC \NWC"6;
"S \NAC"
BN"0"49;
%"TAP"
"1","(-5850,4900)","2","mstr_standard","I272";
;
CDS_LIB"mstr_standard"
BODY_TYPE"PLUMBING"
HDL_TAP"TRUE";
"B \NAC \NWC"6;
"S \NAC"
BN"1"47;
%"TAP"
"1","(-5850,4800)","2","mstr_standard","I273";
;
CDS_LIB"mstr_standard"
BODY_TYPE"PLUMBING"
HDL_TAP"TRUE";
"B \NAC \NWC"6;
"S \NAC"
BN"2"45;
%"TAP"
"1","(-5850,4700)","2","mstr_standard","I274";
;
CDS_LIB"mstr_standard"
BODY_TYPE"PLUMBING"
HDL_TAP"TRUE";
"B \NAC \NWC"6;
"S \NAC"
BN"3"43;
%"TAP"
"1","(-6050,5100)","2","mstr_standard","I275";
;
CDS_LIB"mstr_standard"
BODY_TYPE"PLUMBING"
HDL_TAP"TRUE";
"B \NAC \NWC"9;
"S \NAC"
BN"9"51;
%"TAP"
"1","(-6050,4950)","2","mstr_standard","I276";
;
CDS_LIB"mstr_standard"
BODY_TYPE"PLUMBING"
HDL_TAP"TRUE";
"B \NAC \NWC"10;
"S \NAC"
BN"0"55;
%"TAP"
"1","(-6050,4850)","2","mstr_standard","I277";
;
CDS_LIB"mstr_standard"
BODY_TYPE"PLUMBING"
HDL_TAP"TRUE";
"B \NAC \NWC"10;
"S \NAC"
BN"1"54;
%"TAP"
"1","(-6050,4750)","2","mstr_standard","I278";
;
CDS_LIB"mstr_standard"
BODY_TYPE"PLUMBING"
HDL_TAP"TRUE";
"B \NAC \NWC"10;
"S \NAC"
BN"2"53;
%"TAP"
"1","(-6050,4650)","2","mstr_standard","I279";
;
CDS_LIB"mstr_standard"
BODY_TYPE"PLUMBING"
HDL_TAP"TRUE";
"B \NAC \NWC"10;
"S \NAC"
BN"3"52;
%"TAP"
"1","(-5850,4600)","2","mstr_standard","I280";
;
CDS_LIB"mstr_standard"
BODY_TYPE"PLUMBING"
HDL_TAP"TRUE";
"B \NAC \NWC"6;
"S \NAC"
BN"4"41;
%"TAP"
"1","(-5850,4400)","2","mstr_standard","I281";
;
CDS_LIB"mstr_standard"
BODY_TYPE"PLUMBING"
HDL_TAP"TRUE";
"B \NAC \NWC"6;
"S \NAC"
BN"6"58;
%"TAP"
"1","(-5850,4500)","2","mstr_standard","I282";
;
CDS_LIB"mstr_standard"
BODY_TYPE"PLUMBING"
HDL_TAP"TRUE";
"B \NAC \NWC"6;
"S \NAC"
BN"5"59;
%"TAP"
"1","(-5850,4300)","2","mstr_standard","I283";
;
CDS_LIB"mstr_standard"
BODY_TYPE"PLUMBING"
HDL_TAP"TRUE";
"B \NAC \NWC"6;
"S \NAC"
BN"7"57;
%"TAP"
"1","(-5850,4200)","2","mstr_standard","I284";
;
CDS_LIB"mstr_standard"
BODY_TYPE"PLUMBING"
HDL_TAP"TRUE";
"B \NAC \NWC"6;
"S \NAC"
BN"8"56;
%"TAP"
"1","(-5850,4100)","2","mstr_standard","I285";
;
CDS_LIB"mstr_standard"
BODY_TYPE"PLUMBING"
HDL_TAP"TRUE";
"B \NAC \NWC"6;
"S \NAC"
BN"9"40;
%"TAP"
"1","(-6050,4550)","2","mstr_standard","I286";
;
CDS_LIB"mstr_standard"
BODY_TYPE"PLUMBING"
HDL_TAP"TRUE";
"B \NAC \NWC"10;
"S \NAC"
BN"4"50;
%"TAP"
"1","(-6050,4450)","2","mstr_standard","I287";
;
CDS_LIB"mstr_standard"
BODY_TYPE"PLUMBING"
HDL_TAP"TRUE";
"B \NAC \NWC"10;
"S \NAC"
BN"5"48;
%"TAP"
"1","(-6050,4250)","2","mstr_standard","I288";
;
CDS_LIB"mstr_standard"
BODY_TYPE"PLUMBING"
HDL_TAP"TRUE";
"B \NAC \NWC"10;
"S \NAC"
BN"7"44;
%"TAP"
"1","(-6050,4350)","2","mstr_standard","I289";
;
CDS_LIB"mstr_standard"
BODY_TYPE"PLUMBING"
HDL_TAP"TRUE";
"B \NAC \NWC"10;
"S \NAC"
BN"6"46;
%"TAP"
"1","(-6050,4150)","2","mstr_standard","I290";
;
CDS_LIB"mstr_standard"
BODY_TYPE"PLUMBING"
HDL_TAP"TRUE";
"B \NAC \NWC"10;
"S \NAC"
BN"8"42;
%"TAP"
"1","(-6050,4050)","2","mstr_standard","I295";
;
CDS_LIB"mstr_standard"
BODY_TYPE"PLUMBING"
HDL_TAP"TRUE";
"B \NAC \NWC"10;
"S \NAC"
BN"9"39;
%"TAP"
"1","(-6050,3900)","2","mstr_standard","I296";
;
CDS_LIB"mstr_standard"
BODY_TYPE"PLUMBING"
HDL_TAP"TRUE";
"B \NAC \NWC"7;
"S \NAC"
BN"0"38;
%"TAP"
"1","(-6050,3850)","2","mstr_standard","I297";
;
CDS_LIB"mstr_standard"
BODY_TYPE"PLUMBING"
HDL_TAP"TRUE";
"B \NAC \NWC"7;
"S \NAC"
BN"1"36;
%"TAP"
"1","(-6050,3800)","2","mstr_standard","I298";
;
CDS_LIB"mstr_standard"
BODY_TYPE"PLUMBING"
HDL_TAP"TRUE";
"B \NAC \NWC"7;
"S \NAC"
BN"2"34;
%"TAP"
"1","(-6050,3750)","2","mstr_standard","I299";
;
CDS_LIB"mstr_standard"
BODY_TYPE"PLUMBING"
HDL_TAP"TRUE";
"B \NAC \NWC"7;
"S \NAC"
BN"3"32;
%"TAP"
"1","(-6050,3700)","2","mstr_standard","I300";
;
CDS_LIB"mstr_standard"
BODY_TYPE"PLUMBING"
HDL_TAP"TRUE";
"B \NAC \NWC"7;
"S \NAC"
BN"4"30;
%"TAP"
"1","(-6050,3650)","2","mstr_standard","I301";
;
CDS_LIB"mstr_standard"
BODY_TYPE"PLUMBING"
HDL_TAP"TRUE";
"B \NAC \NWC"7;
"S \NAC"
BN"5"28;
%"TAP"
"1","(-6050,3600)","2","mstr_standard","I302";
;
CDS_LIB"mstr_standard"
BODY_TYPE"PLUMBING"
HDL_TAP"TRUE";
"B \NAC \NWC"7;
"S \NAC"
BN"6"26;
%"TAP"
"1","(-6050,3500)","2","mstr_standard","I303";
;
CDS_LIB"mstr_standard"
BODY_TYPE"PLUMBING"
HDL_TAP"TRUE";
"B \NAC \NWC"8;
"S \NAC"
BN"0"37;
%"TAP"
"1","(-6050,3450)","2","mstr_standard","I304";
;
CDS_LIB"mstr_standard"
BODY_TYPE"PLUMBING"
HDL_TAP"TRUE";
"B \NAC \NWC"8;
"S \NAC"
BN"1"35;
%"TAP"
"1","(-6050,3400)","2","mstr_standard","I305";
;
CDS_LIB"mstr_standard"
BODY_TYPE"PLUMBING"
HDL_TAP"TRUE";
"B \NAC \NWC"8;
"S \NAC"
BN"2"33;
%"TAP"
"1","(-6050,3350)","2","mstr_standard","I306";
;
CDS_LIB"mstr_standard"
BODY_TYPE"PLUMBING"
HDL_TAP"TRUE";
"B \NAC \NWC"8;
"S \NAC"
BN"3"31;
%"TAP"
"1","(-6050,3300)","2","mstr_standard","I307";
;
CDS_LIB"mstr_standard"
BODY_TYPE"PLUMBING"
HDL_TAP"TRUE";
"B \NAC \NWC"8;
"S \NAC"
BN"4"29;
%"TAP"
"1","(-6050,3250)","2","mstr_standard","I308";
;
CDS_LIB"mstr_standard"
BODY_TYPE"PLUMBING"
HDL_TAP"TRUE";
"B \NAC \NWC"8;
"S \NAC"
BN"5"27;
%"TAP"
"1","(-6050,3200)","2","mstr_standard","I309";
;
CDS_LIB"mstr_standard"
BODY_TYPE"PLUMBING"
HDL_TAP"TRUE";
"B \NAC \NWC"8;
"S \NAC"
BN"6"25;
%"Q_RES"
"1","(-6975,2200)","0","pure_quanta","I323";
;
LOCATION"R381"
$SEC"1"
CDS_SEC"1"
TOLERANCE"1%"
VALUE"15   "
PART_NUMBER"CS01502FB11"
PACK_TYPE"0402LF"
CDS_LIB"pure_quanta"
WATTAGE"1/16W"
MATERIAL"CHIP";
"B"
$PN"2"13;
"A"
$PN"1"11;
END.
